# S9S_MB_2U (Grand Teton) — schematic netlist excerpt (pin names and nets, part order shuffled) for the footprints in the layout excerpt that follows; sources: Cadence DE-HDL packaged netlist, KiCad conversion of 03242023_DA0F0TMBIJ0_F0T_Motherboard_J_brd_V01_OCP.brd

R145  Q_RES  4.75K 1% EMPTY  pkg 0402LF  page 197 : A = PVNN_TERM_CPU0 ; B = PECI_PCH_R
R120  Q_RES  10M 1% CHIP  pkg 0603LF  page 179 : A = XTAL_PCH_RTC2_R ; B = XTAL_PCH_RTC1

(kicad_pcb
	(version 20260206)
	(generator "pcbnew")
	(generator_version "10.0")
	(general
		(thickness 1.6)
		(legacy_teardrops no)
	)
	(paper "A4")
	(title_block
		(title "03242023_DA0F0TMBIJ0_F0T_Motherboard_J_brd_V01_OCP.brd")
		(comment 1 "Grand Teton / footprints 2289-2290 of 6105")
	)
	(layers
		(0 "F.Cu" signal "TOP")
		(4 "In1.Cu" signal "GND")
		(6 "In2.Cu" signal "IN1")
		(8 "In3.Cu" signal "GND1")
		(10 "In4.Cu" signal "IN2")
		(12 "In5.Cu" signal "GND2")
		(14 "In6.Cu" signal "IN3")
		(16 "In7.Cu" signal "GND3")
		(18 "In8.Cu" signal "VCC")
		(20 "In9.Cu" signal "VCC1")
		(22 "In10.Cu" signal "GND4")
		(24 "In11.Cu" signal "IN4")
		(26 "In12.Cu" signal "GND5")
		(28 "In13.Cu" signal "IN5")
		(30 "In14.Cu" signal "GND6")
		(32 "In15.Cu" signal "IN6")
		(34 "In16.Cu" signal "GND7")
		(2 "B.Cu" signal "BOTTOM")
		(9 "F.Adhes" user "F.Adhesive")
		(11 "B.Adhes" user "B.Adhesive")
		(13 "F.Paste" user "Package Geometry/Pastemask Top")
		(15 "B.Paste" user "Package Geometry/Pastemask Bottom")
		(5 "F.SilkS" user "Ref Des/Silkscreen Top")
		(7 "B.SilkS" user "Ref Des/Silkscreen Bottom")
		(1 "F.Mask" user "Board Geometry/Soldermask Top")
		(3 "B.Mask" user "Board Geometry/Soldermask Bottom")
		(17 "Dwgs.User" user "User.Drawings")
		(19 "Cmts.User" user "User.Comments")
		(21 "Eco1.User" user "User.Eco1")
		(23 "Eco2.User" user "User.Eco2")
		(25 "Edge.Cuts" user "Board Geometry/Outline")
		(27 "Margin" user)
		(31 "F.CrtYd" user "Package Geometry/Place Bound Top")
		(29 "B.CrtYd" user "Package Geometry/Place Bound Bottom")
		(35 "F.Fab" user "Ref Des/Assembly Top")
		(33 "B.Fab" user "Ref Des/Assembly Bottom")
	)
	(footprint ""
		(layer "F.Cu")
		(at 307.77688 -53.050948 90)
		(property "Reference" "R145"
			(at 0 0 90)
			(layer "F.SilkS")
			(hide yes)
			(effects
				(font
					(size 1.27 1.27)
				)
			)
		)
		(property "Value" ""
			(at 0 0 90)
			(layer "F.Fab")
			(effects
				(font
					(size 1.27 1.27)
				)
			)
		)
		(duplicate_pad_numbers_are_jumpers no)
		(fp_line
			(start 0.7874 -0.4064)
			(end 0.7874 0.4064)
			(stroke
				(width 0.1524)
				(type default)
			)
			(layer "F.SilkS")
		)
		(fp_line
			(start -0.7874 -0.4064)
			(end 0.7874 -0.4064)
			(stroke
				(width 0.1524)
				(type default)
			)
			(layer "F.SilkS")
		)
		(fp_line
			(start 0.7874 0.4064)
			(end -0.7874 0.4064)
			(stroke
				(width 0.1524)
				(type default)
			)
			(layer "F.SilkS")
		)
		(fp_line
			(start -0.7874 0.4064)
			(end -0.7874 -0.4064)
			(stroke
				(width 0.1524)
				(type default)
			)
			(layer "F.SilkS")
		)
		(fp_line
			(start -0.12065 -0.305054)
			(end -0.12065 -0.2794)
			(stroke
				(width 0.1)
				(type default)
			)
			(layer "F.Fab")
		)
		(fp_line
			(start -0.67945 -0.305054)
			(end -0.12065 -0.305054)
			(stroke
				(width 0.1)
				(type default)
			)
			(layer "F.Fab")
		)
		(fp_line
			(start 0.67945 -0.3048)
			(end 0.67945 0.3048)
			(stroke
				(width 0.1)
				(type default)
			)
			(layer "F.Fab")
		)
		(fp_line
			(start 0.12065 -0.3048)
			(end 0.67945 -0.3048)
			(stroke
				(width 0.1)
				(type default)
			)
			(layer "F.Fab")
		)
		(fp_line
			(start 0.12065 -0.2794)
			(end 0.12065 -0.3048)
			(stroke
				(width 0.1)
				(type default)
			)
			(layer "F.Fab")
		)
		(fp_line
			(start -0.12065 -0.2794)
			(end 0.12065 -0.2794)
			(stroke
				(width 0.1)
				(type default)
			)
			(layer "F.Fab")
		)
		(fp_line
			(start 0.120396 0.2794)
			(end -0.12065 0.2794)
			(stroke
				(width 0.1)
				(type default)
			)
			(layer "F.Fab")
		)
		(fp_line
			(start -0.12065 0.2794)
			(end -0.12065 0.3048)
			(stroke
				(width 0.1)
				(type default)
			)
			(layer "F.Fab")
		)
		(fp_line
			(start 0.67945 0.3048)
			(end 0.120396 0.3048)
			(stroke
				(width 0.1)
				(type default)
			)
			(layer "F.Fab")
		)
		(fp_line
			(start 0.120396 0.3048)
			(end 0.120396 0.2794)
			(stroke
				(width 0.1)
				(type default)
			)
			(layer "F.Fab")
		)
		(fp_line
			(start -0.12065 0.3048)
			(end -0.67945 0.3048)
			(stroke
				(width 0.1)
				(type default)
			)
			(layer "F.Fab")
		)
		(fp_line
			(start -0.67945 0.3048)
			(end -0.67945 -0.305054)
			(stroke
				(width 0.1)
				(type default)
			)
			(layer "F.Fab")
		)
		(pad "1" smd circle
			(at -0.40005 0 90)
			(size 0 0)
			(layers "F.Cu" "F.Mask" "F.Paste")
			(net "PVNN_TERM_CPU0")
		)
		(pad "2" smd circle
			(at 0.40005 0 90)
			(size 0 0)
			(layers "F.Cu" "F.Mask" "F.Paste")
			(net "PECI_PCH_R")
		)
	)
	(footprint ""
		(layer "F.Cu")
		(at 324.919594 -32.371538 135)
		(property "Reference" "R120"
			(at 0 0 135)
			(layer "F.SilkS")
			(hide yes)
			(effects
				(font
					(size 1.27 1.27)
				)
			)
		)
		(property "Value" ""
			(at 0 0 135)
			(layer "F.Fab")
			(effects
				(font
					(size 1.27 1.27)
				)
			)
		)
		(duplicate_pad_numbers_are_jumpers no)
		(fp_line
			(start 1.295492 -0.584255)
			(end 1.295492 0.584255)
			(stroke
				(width 0.1524)
				(type default)
			)
			(layer "F.SilkS")
		)
		(fp_line
			(start 1.295492 0.584255)
			(end -1.295492 0.584255)
			(stroke
				(width 0.1524)
				(type default)
			)
			(layer "F.SilkS")
		)
		(fp_line
			(start -1.295492 -0.584255)
			(end 1.295492 -0.584255)
			(stroke
				(width 0.1524)
				(type default)
			)
			(layer "F.SilkS")
		)
		(fp_line
			(start -1.295492 0.584255)
			(end -1.295492 -0.584255)
			(stroke
				(width 0.1524)
				(type default)
			)
			(layer "F.SilkS")
		)
		(fp_line
			(start 1.193656 -0.406626)
			(end 1.193835 0.406446)
			(stroke
				(width 0.1)
				(type default)
			)
			(layer "F.Fab")
		)
		(fp_line
			(start 0.863541 -0.457275)
			(end 0.863541 -0.406626)
			(stroke
				(width 0.1)
				(type default)
			)
			(layer "F.Fab")
		)
		(fp_line
			(start 0.863541 -0.406626)
			(end 1.193656 -0.406626)
			(stroke
				(width 0.1)
				(type default)
			)
			(layer "F.Fab")
		)
		(fp_line
			(start 1.193835 0.406446)
			(end 0.863721 0.406446)
			(stroke
				(width 0.1)
				(type default)
			)
			(layer "F.Fab")
		)
		(fp_line
			(start 0.863721 0.406446)
			(end 0.863541 0.457275)
			(stroke
				(width 0.1)
				(type default)
			)
			(layer "F.Fab")
		)
		(fp_line
			(start 0.863541 0.457275)
			(end -0.863541 0.457275)
			(stroke
				(width 0.1)
				(type default)
			)
			(layer "F.Fab")
		)
		(fp_line
			(start -0.863541 -0.457275)
			(end 0.863541 -0.457275)
			(stroke
				(width 0.1)
				(type default)
			)
			(layer "F.Fab")
		)
		(fp_line
			(start -0.863541 -0.406626)
			(end -0.863541 -0.457275)
			(stroke
				(width 0.1)
				(type default)
			)
			(layer "F.Fab")
		)
		(fp_line
			(start -1.193656 -0.406626)
			(end -0.863541 -0.406626)
			(stroke
				(width 0.1)
				(type default)
			)
			(layer "F.Fab")
		)
		(fp_line
			(start -0.863721 0.406446)
			(end -1.193835 0.406446)
			(stroke
				(width 0.1)
				(type default)
			)
			(layer "F.Fab")
		)
		(fp_line
			(start -0.863541 0.431771)
			(end -0.863721 0.406446)
			(stroke
				(width 0.1)
				(type default)
			)
			(layer "F.Fab")
		)
		(fp_line
			(start -0.863541 0.457275)
			(end -0.863541 0.431771)
			(stroke
				(width 0.1)
				(type default)
			)
			(layer "F.Fab")
		)
		(fp_line
			(start -1.193835 0.406446)
			(end -1.193656 -0.406626)
			(stroke
				(width 0.1)
				(type default)
			)
			(layer "F.Fab")
		)
		(pad "1" smd rect
			(at -0.7366 0 45)
			(size 0.7112 0.8128)
			(layers "F.Cu" "F.Mask" "F.Paste")
			(net "XTAL_PCH_RTC2_R")
		)
		(pad "2" smd rect
			(at 0.7366 0 45)
			(size 0.7112 0.8128)
			(layers "F.Cu" "F.Mask" "F.Paste")
			(net "XTAL_PCH_RTC1")
		)
	)
)
